(kicad_pcb
	(version 20260206)
	(generator "pcbnew")
	(generator_version "10.0")
	(general
		(thickness 1.6)
		(legacy_teardrops no)
	)
	(paper "A4")
	(title_block
		(title "03242023_DA0F0TMBIJ0_F0T_Motherboard_J_brd_V01_OCP.brd")
		(comment 1 "Grand Teton / footprints 5432-5438 of 6105")
	)
	(layers
		(0 "F.Cu" signal "TOP")
		(4 "In1.Cu" signal "GND")
		(6 "In2.Cu" signal "IN1")
		(8 "In3.Cu" signal "GND1")
		(10 "In4.Cu" signal "IN2")
		(12 "In5.Cu" signal "GND2")
		(14 "In6.Cu" signal "IN3")
		(16 "In7.Cu" signal "GND3")
		(18 "In8.Cu" signal "VCC")
		(20 "In9.Cu" signal "VCC1")
		(22 "In10.Cu" signal "GND4")
		(24 "In11.Cu" signal "IN4")
		(26 "In12.Cu" signal "GND5")
		(28 "In13.Cu" signal "IN5")
		(30 "In14.Cu" signal "GND6")
		(32 "In15.Cu" signal "IN6")
		(34 "In16.Cu" signal "GND7")
		(2 "B.Cu" signal "BOTTOM")
		(9 "F.Adhes" user "F.Adhesive")
		(11 "B.Adhes" user "B.Adhesive")
		(13 "F.Paste" user "Package Geometry/Pastemask Top")
		(15 "B.Paste" user "Package Geometry/Pastemask Bottom")
		(5 "F.SilkS" user "Ref Des/Silkscreen Top")
		(7 "B.SilkS" user "Ref Des/Silkscreen Bottom")
		(1 "F.Mask" user "Board Geometry/Soldermask Top")
		(3 "B.Mask" user "Board Geometry/Soldermask Bottom")
		(17 "Dwgs.User" user "User.Drawings")
		(19 "Cmts.User" user "User.Comments")
		(21 "Eco1.User" user "User.Eco1")
		(23 "Eco2.User" user "User.Eco2")
		(25 "Edge.Cuts" user "Board Geometry/Outline")
		(27 "Margin" user)
		(31 "F.CrtYd" user "Package Geometry/Place Bound Top")
		(29 "B.CrtYd" user "Package Geometry/Place Bound Bottom")
		(35 "F.Fab" user "Ref Des/Assembly Top")
		(33 "B.Fab" user "Ref Des/Assembly Bottom")
	)
	(footprint ""
		(layer "B.Cu")
		(at 291.004498 -400.999452 -90)
		(property "Reference" "PR2521"
			(at 0 0 90)
			(layer "B.SilkS")
			(hide yes)
			(effects
				(font
					(size 1.27 1.27)
				)
				(justify mirror)
			)
		)
		(property "Value" ""
			(at 0 0 90)
			(layer "B.Fab")
			(effects
				(font
					(size 1.27 1.27)
				)
				(justify mirror)
			)
		)
		(duplicate_pad_numbers_are_jumpers no)
		(fp_line
			(start -0.7874 0.4064)
			(end 0.7874 0.4064)
			(stroke
				(width 0.1524)
				(type default)
			)
			(layer "B.SilkS")
		)
		(fp_line
			(start 0.7874 0.4064)
			(end 0.7874 -0.4064)
			(stroke
				(width 0.1524)
				(type default)
			)
			(layer "B.SilkS")
		)
		(fp_line
			(start -0.7874 -0.4064)
			(end -0.7874 0.4064)
			(stroke
				(width 0.1524)
				(type default)
			)
			(layer "B.SilkS")
		)
		(fp_line
			(start 0.7874 -0.4064)
			(end -0.7874 -0.4064)
			(stroke
				(width 0.1524)
				(type default)
			)
			(layer "B.SilkS")
		)
		(fp_line
			(start -0.67945 0.3048)
			(end -0.120396 0.3048)
			(stroke
				(width 0.1)
				(type default)
			)
			(layer "B.Fab")
		)
		(fp_line
			(start -0.120396 0.3048)
			(end -0.120396 0.2794)
			(stroke
				(width 0.1)
				(type default)
			)
			(layer "B.Fab")
		)
		(fp_line
			(start 0.12065 0.3048)
			(end 0.67945 0.3048)
			(stroke
				(width 0.1)
				(type default)
			)
			(layer "B.Fab")
		)
		(fp_line
			(start 0.67945 0.3048)
			(end 0.67945 -0.305054)
			(stroke
				(width 0.1)
				(type default)
			)
			(layer "B.Fab")
		)
		(fp_line
			(start -0.120396 0.2794)
			(end 0.12065 0.2794)
			(stroke
				(width 0.1)
				(type default)
			)
			(layer "B.Fab")
		)
		(fp_line
			(start 0.12065 0.2794)
			(end 0.12065 0.3048)
			(stroke
				(width 0.1)
				(type default)
			)
			(layer "B.Fab")
		)
		(fp_line
			(start -0.12065 -0.2794)
			(end -0.12065 -0.3048)
			(stroke
				(width 0.1)
				(type default)
			)
			(layer "B.Fab")
		)
		(fp_line
			(start 0.12065 -0.2794)
			(end -0.12065 -0.2794)
			(stroke
				(width 0.1)
				(type default)
			)
			(layer "B.Fab")
		)
		(fp_line
			(start -0.67945 -0.3048)
			(end -0.67945 0.3048)
			(stroke
				(width 0.1)
				(type default)
			)
			(layer "B.Fab")
		)
		(fp_line
			(start -0.12065 -0.3048)
			(end -0.67945 -0.3048)
			(stroke
				(width 0.1)
				(type default)
			)
			(layer "B.Fab")
		)
		(fp_line
			(start 0.12065 -0.305054)
			(end 0.12065 -0.2794)
			(stroke
				(width 0.1)
				(type default)
			)
			(layer "B.Fab")
		)
		(fp_line
			(start 0.67945 -0.305054)
			(end 0.12065 -0.305054)
			(stroke
				(width 0.1)
				(type default)
			)
			(layer "B.Fab")
		)
		(pad "1" smd circle
			(at 0.40005 0 90)
			(size 0 0)
			(layers "B.Cu" "B.Mask" "B.Paste")
			(net "P12V_HSC_SENSE2_P")
		)
		(pad "2" smd circle
			(at -0.40005 0 90)
			(size 0 0)
			(layers "B.Cu" "B.Mask" "B.Paste")
			(net "P12V_HSC_SENSE2_R2_P")
		)
	)
	(footprint ""
		(layer "B.Cu")
		(at 176.955704 -114.575336)
		(property "Reference" "C1907"
			(at 0 0 0)
			(layer "B.SilkS")
			(hide yes)
			(effects
				(font
					(size 1.27 1.27)
				)
				(justify mirror)
			)
		)
		(property "Value" ""
			(at 0 0 0)
			(layer "B.Fab")
			(effects
				(font
					(size 1.27 1.27)
				)
				(justify mirror)
			)
		)
		(duplicate_pad_numbers_are_jumpers no)
		(fp_line
			(start -0.69215 -0.2921)
			(end -0.69215 0.2921)
			(stroke
				(width 0.1524)
				(type default)
			)
			(layer "B.SilkS")
		)
		(fp_line
			(start -0.69215 0.2921)
			(end 0.69215 0.2921)
			(stroke
				(width 0.1524)
				(type default)
			)
			(layer "B.SilkS")
		)
		(fp_line
			(start 0.69215 -0.2921)
			(end -0.69215 -0.2921)
			(stroke
				(width 0.1524)
				(type default)
			)
			(layer "B.SilkS")
		)
		(fp_line
			(start 0.69215 0.2921)
			(end 0.69215 -0.2921)
			(stroke
				(width 0.1524)
				(type default)
			)
			(layer "B.SilkS")
		)
		(fp_line
			(start -0.51435 -0.2794)
			(end -0.51435 0.2794)
			(stroke
				(width 0.1)
				(type default)
			)
			(layer "B.Fab")
		)
		(fp_line
			(start -0.51435 0.2794)
			(end 0.51435 0.2794)
			(stroke
				(width 0.1)
				(type default)
			)
			(layer "B.Fab")
		)
		(fp_line
			(start 0.51435 -0.2794)
			(end -0.51435 -0.2794)
			(stroke
				(width 0.1)
				(type default)
			)
			(layer "B.Fab")
		)
		(fp_line
			(start 0.51435 0.2794)
			(end 0.51435 -0.2794)
			(stroke
				(width 0.1)
				(type default)
			)
			(layer "B.Fab")
		)
		(pad "1" smd circle
			(at 0.40005 0 180)
			(size 0 0)
			(layers "B.Cu" "B.Mask" "B.Paste")
			(net "VCC_PLD_CORE")
		)
		(pad "2" smd circle
			(at -0.40005 0 180)
			(size 0 0)
			(layers "B.Cu" "B.Mask" "B.Paste")
			(net "GND")
		)
		(zone
			(layer "B.Cu")
			(hatch none 0.5)
			(connect_pads
				(clearance 0)
			)
			(min_thickness 0.25)
			(keepout
				(tracks not_allowed)
				(vias allowed)
				(pads allowed)
				(copperpour not_allowed)
				(footprints allowed)
			)
			(placement
				(enabled no)
				(sheetname "")
			)
			(fill
				(thermal_gap 0.5)
				(thermal_bridge_width 0.5)
				(island_removal_mode 0)
			)
			(polygon
				(pts
					(xy 177.146204 -114.487706) (xy 177.054764 -114.42954) (xy 176.855374 -114.42954) (xy 176.765204 -114.487706)
					(xy 176.765204 -114.662966) (xy 176.855374 -114.721386) (xy 177.054764 -114.721386) (xy 177.146204 -114.66322)
				)
			)
		)
	)
	(footprint ""
		(layer "B.Cu")
		(at 359.960418 -294.009826)
		(property "Reference" "C374"
			(at 0 0 0)
			(layer "B.SilkS")
			(hide yes)
			(effects
				(font
					(size 1.27 1.27)
				)
				(justify mirror)
			)
		)
		(property "Value" ""
			(at 0 0 0)
			(layer "B.Fab")
			(effects
				(font
					(size 1.27 1.27)
				)
				(justify mirror)
			)
		)
		(duplicate_pad_numbers_are_jumpers no)
		(fp_line
			(start -1.524 -0.762)
			(end -1.524 0.762)
			(stroke
				(width 0.1524)
				(type default)
			)
			(layer "B.SilkS")
		)
		(fp_line
			(start -1.524 0.762)
			(end 1.524 0.762)
			(stroke
				(width 0.1524)
				(type default)
			)
			(layer "B.SilkS")
		)
		(fp_line
			(start 1.524 -0.762)
			(end -1.524 -0.762)
			(stroke
				(width 0.1524)
				(type default)
			)
			(layer "B.SilkS")
		)
		(fp_line
			(start 1.524 0.762)
			(end 1.524 -0.762)
			(stroke
				(width 0.1524)
				(type default)
			)
			(layer "B.SilkS")
		)
		(fp_line
			(start -1.1049 -0.724916)
			(end 1.1049 -0.724916)
			(stroke
				(width 0.1)
				(type default)
			)
			(layer "B.Fab")
		)
		(fp_line
			(start -1.1049 0.724916)
			(end -1.1049 -0.724916)
			(stroke
				(width 0.1)
				(type default)
			)
			(layer "B.Fab")
		)
		(fp_line
			(start 1.1049 -0.724916)
			(end 1.1049 0.724916)
			(stroke
				(width 0.1)
				(type default)
			)
			(layer "B.Fab")
		)
		(fp_line
			(start 1.1049 0.724916)
			(end -1.1049 0.724916)
			(stroke
				(width 0.1)
				(type default)
			)
			(layer "B.Fab")
		)
		(pad "1" smd rect
			(at 0.889 0)
			(size 1.016 1.27)
			(layers "B.Cu" "B.Mask" "B.Paste")
			(net "PVCCIN_CPU0")
		)
		(pad "2" smd rect
			(at -0.889 0)
			(size 1.016 1.27)
			(layers "B.Cu" "B.Mask" "B.Paste")
			(net "GND")
		)
	)
	(footprint ""
		(layer "B.Cu")
		(at 250.30303 -44.979082 90)
		(property "Reference" "R3958"
			(at 0 0 90)
			(layer "B.SilkS")
			(hide yes)
			(effects
				(font
					(size 1.27 1.27)
				)
				(justify mirror)
			)
		)
		(property "Value" ""
			(at 0 0 90)
			(layer "B.Fab")
			(effects
				(font
					(size 1.27 1.27)
				)
				(justify mirror)
			)
		)
		(duplicate_pad_numbers_are_jumpers no)
		(fp_line
			(start 0.7874 -0.4064)
			(end -0.7874 -0.4064)
			(stroke
				(width 0.1524)
				(type default)
			)
			(layer "B.SilkS")
		)
		(fp_line
			(start -0.7874 -0.4064)
			(end -0.7874 0.4064)
			(stroke
				(width 0.1524)
				(type default)
			)
			(layer "B.SilkS")
		)
		(fp_line
			(start 0.7874 0.4064)
			(end 0.7874 -0.4064)
			(stroke
				(width 0.1524)
				(type default)
			)
			(layer "B.SilkS")
		)
		(fp_line
			(start -0.7874 0.4064)
			(end 0.7874 0.4064)
			(stroke
				(width 0.1524)
				(type default)
			)
			(layer "B.SilkS")
		)
		(fp_line
			(start 0.67945 -0.305054)
			(end 0.12065 -0.305054)
			(stroke
				(width 0.1)
				(type default)
			)
			(layer "B.Fab")
		)
		(fp_line
			(start 0.12065 -0.305054)
			(end 0.12065 -0.2794)
			(stroke
				(width 0.1)
				(type default)
			)
			(layer "B.Fab")
		)
		(fp_line
			(start -0.12065 -0.3048)
			(end -0.67945 -0.3048)
			(stroke
				(width 0.1)
				(type default)
			)
			(layer "B.Fab")
		)
		(fp_line
			(start -0.67945 -0.3048)
			(end -0.67945 0.3048)
			(stroke
				(width 0.1)
				(type default)
			)
			(layer "B.Fab")
		)
		(fp_line
			(start 0.12065 -0.2794)
			(end -0.12065 -0.2794)
			(stroke
				(width 0.1)
				(type default)
			)
			(layer "B.Fab")
		)
		(fp_line
			(start -0.12065 -0.2794)
			(end -0.12065 -0.3048)
			(stroke
				(width 0.1)
				(type default)
			)
			(layer "B.Fab")
		)
		(fp_line
			(start 0.12065 0.2794)
			(end 0.12065 0.3048)
			(stroke
				(width 0.1)
				(type default)
			)
			(layer "B.Fab")
		)
		(fp_line
			(start -0.120396 0.2794)
			(end 0.12065 0.2794)
			(stroke
				(width 0.1)
				(type default)
			)
			(layer "B.Fab")
		)
		(fp_line
			(start 0.67945 0.3048)
			(end 0.67945 -0.305054)
			(stroke
				(width 0.1)
				(type default)
			)
			(layer "B.Fab")
		)
		(fp_line
			(start 0.12065 0.3048)
			(end 0.67945 0.3048)
			(stroke
				(width 0.1)
				(type default)
			)
			(layer "B.Fab")
		)
		(fp_line
			(start -0.120396 0.3048)
			(end -0.120396 0.2794)
			(stroke
				(width 0.1)
				(type default)
			)
			(layer "B.Fab")
		)
		(fp_line
			(start -0.67945 0.3048)
			(end -0.120396 0.3048)
			(stroke
				(width 0.1)
				(type default)
			)
			(layer "B.Fab")
		)
		(pad "1" smd circle
			(at 0.40005 0 270)
			(size 0 0)
			(layers "B.Cu" "B.Mask" "B.Paste")
			(net "P12V_E1S_UV_0_R")
		)
		(pad "2" smd circle
			(at -0.40005 0 270)
			(size 0 0)
			(layers "B.Cu" "B.Mask" "B.Paste")
			(net "P12V_E1S_UV_0")
		)
	)
	(footprint ""
		(layer "B.Cu")
		(at 369.477036 -187.181744)
		(property "Reference" "U28"
			(at -0.760476 -4.318254 0)
			(unlocked yes)
			(layer "B.SilkS")
			(effects
				(font
					(size 0.7874 0.5842)
					(thickness 0.1524)
				)
				(justify left mirror)
			)
		)
		(property "Value" ""
			(at 0 0 0)
			(layer "B.Fab")
			(effects
				(font
					(size 1.27 1.27)
				)
				(justify mirror)
			)
		)
		(duplicate_pad_numbers_are_jumpers no)
		(fp_line
			(start -1.463548 -1.549908)
			(end -1.463548 1.549908)
			(stroke
				(width 0.1524)
				(type default)
			)
			(layer "B.SilkS")
		)
		(fp_line
			(start -1.463548 1.549908)
			(end 1.463548 1.549908)
			(stroke
				(width 0.1524)
				(type default)
			)
			(layer "B.SilkS")
		)
		(fp_line
			(start -0.762 -1.549908)
			(end -1.463548 -1.549908)
			(stroke
				(width 0.1524)
				(type default)
			)
			(layer "B.SilkS")
		)
		(fp_line
			(start 0 -0.762)
			(end -0.762 -1.549908)
			(stroke
				(width 0.1524)
				(type default)
			)
			(layer "B.SilkS")
		)
		(fp_line
			(start 0.787908 -1.549908)
			(end 0 -0.762)
			(stroke
				(width 0.1524)
				(type default)
			)
			(layer "B.SilkS")
		)
		(fp_line
			(start 1.463548 -1.549908)
			(end 0.787908 -1.549908)
			(stroke
				(width 0.1524)
				(type default)
			)
			(layer "B.SilkS")
		)
		(fp_line
			(start 1.463548 1.549908)
			(end 1.463548 -1.549908)
			(stroke
				(width 0.1524)
				(type default)
			)
			(layer "B.SilkS")
		)
		(fp_poly
			(pts
				(xy 2.848356 -2.227326) (xy 3.360674 -1.878584) (xy 2.7559 -1.54051)
			)
			(stroke
				(width 0)
				(type default)
			)
			(fill yes)
			(layer "B.SilkS")
		)
		(fp_line
			(start -1.549908 -1.549908)
			(end -1.549908 1.549908)
			(stroke
				(width 0.1)
				(type default)
			)
			(layer "B.Fab")
		)
		(fp_line
			(start -1.549908 1.549908)
			(end 1.549908 1.549908)
			(stroke
				(width 0.1)
				(type default)
			)
			(layer "B.Fab")
		)
		(fp_line
			(start 1.549908 -1.549908)
			(end -1.549908 -1.549908)
			(stroke
				(width 0.1)
				(type default)
			)
			(layer "B.Fab")
		)
		(fp_line
			(start 1.549908 1.549908)
			(end 1.549908 -1.549908)
			(stroke
				(width 0.1)
				(type default)
			)
			(layer "B.Fab")
		)
		(fp_poly
			(pts
				(xy 3.4798 -1.359916) (xy 2.86004 -1.050036) (xy 3.4798 -0.740156)
			)
			(stroke
				(width 0)
				(type default)
			)
			(fill yes)
			(layer "B.Fab")
		)
		(pad "1" smd rect
			(at 2.175002 -1.050036 90)
			(size 0.6096 1.1684)
			(layers "B.Cu" "B.Mask" "B.Paste")
			(net "PVNN_TERM_CPU0")
		)
		(pad "2" smd rect
			(at 2.175002 -0.32512 90)
			(size 0.4318 1.1684)
			(layers "B.Cu" "B.Mask" "B.Paste")
			(net "SMB_PEHPCPU0_GTL_R_SCL")
		)
		(pad "3" smd rect
			(at 2.175002 0.32512 90)
			(size 0.4318 1.1684)
			(layers "B.Cu" "B.Mask" "B.Paste")
			(net "SMB_PEHPCPU0_GTL_R_SDA")
		)
		(pad "4" smd rect
			(at 2.175002 1.050036 90)
			(size 0.6096 1.1684)
			(layers "B.Cu" "B.Mask" "B.Paste")
			(net "GND")
		)
		(pad "5" smd rect
			(at -2.175002 1.050036 90)
			(size 0.6096 1.1684)
			(layers "B.Cu" "B.Mask" "B.Paste")
			(net "TP_SMB_PEHPCPU0_EN")
		)
		(pad "6" smd rect
			(at -2.175002 0.32512 90)
			(size 0.4318 1.1684)
			(layers "B.Cu" "B.Mask" "B.Paste")
			(net "SMB_PEHPCPU0_LVC3_SDA_R0")
		)
		(pad "7" smd rect
			(at -2.175002 -0.32512 90)
			(size 0.4318 1.1684)
			(layers "B.Cu" "B.Mask" "B.Paste")
			(net "SMB_PEHPCPU0_LVC3_SCL_R0")
		)
		(pad "8" smd rect
			(at -2.175002 -1.050036 90)
			(size 0.6096 1.1684)
			(layers "B.Cu" "B.Mask" "B.Paste")
			(net "P3V3_AUX")
		)
	)
	(footprint ""
		(layer "B.Cu")
		(at 111.310928 -210.194144)
		(property "Reference" "C455"
			(at 0 0 0)
			(layer "B.SilkS")
			(hide yes)
			(effects
				(font
					(size 1.27 1.27)
				)
				(justify mirror)
			)
		)
		(property "Value" ""
			(at 0 0 0)
			(layer "B.Fab")
			(effects
				(font
					(size 1.27 1.27)
				)
				(justify mirror)
			)
		)
		(duplicate_pad_numbers_are_jumpers no)
		(fp_line
			(start -1.524 -0.762)
			(end -1.524 0.762)
			(stroke
				(width 0.1524)
				(type default)
			)
			(layer "B.SilkS")
		)
		(fp_line
			(start -1.524 0.762)
			(end 1.524 0.762)
			(stroke
				(width 0.1524)
				(type default)
			)
			(layer "B.SilkS")
		)
		(fp_line
			(start 1.524 -0.762)
			(end -1.524 -0.762)
			(stroke
				(width 0.1524)
				(type default)
			)
			(layer "B.SilkS")
		)
		(fp_line
			(start 1.524 0.762)
			(end 1.524 -0.762)
			(stroke
				(width 0.1524)
				(type default)
			)
			(layer "B.SilkS")
		)
		(fp_line
			(start -1.1049 -0.724916)
			(end 1.1049 -0.724916)
			(stroke
				(width 0.1)
				(type default)
			)
			(layer "B.Fab")
		)
		(fp_line
			(start -1.1049 0.724916)
			(end -1.1049 -0.724916)
			(stroke
				(width 0.1)
				(type default)
			)
			(layer "B.Fab")
		)
		(fp_line
			(start 1.1049 -0.724916)
			(end 1.1049 0.724916)
			(stroke
				(width 0.1)
				(type default)
			)
			(layer "B.Fab")
		)
		(fp_line
			(start 1.1049 0.724916)
			(end -1.1049 0.724916)
			(stroke
				(width 0.1)
				(type default)
			)
			(layer "B.Fab")
		)
		(pad "1" smd rect
			(at 0.889 0)
			(size 1.016 1.27)
			(layers "B.Cu" "B.Mask" "B.Paste")
			(net "PVCCD_HV_CPU1")
		)
		(pad "2" smd rect
			(at -0.889 0)
			(size 1.016 1.27)
			(layers "B.Cu" "B.Mask" "B.Paste")
			(net "GND")
		)
	)
	(footprint ""
		(layer "B.Cu")
		(at 205.434438 -110.47095 -90)
		(property "Reference" "R128"
			(at 0 0 90)
			(layer "B.SilkS")
			(hide yes)
			(effects
				(font
					(size 1.27 1.27)
				)
				(justify mirror)
			)
		)
		(property "Value" ""
			(at 0 0 90)
			(layer "B.Fab")
			(effects
				(font
					(size 1.27 1.27)
				)
				(justify mirror)
			)
		)
		(duplicate_pad_numbers_are_jumpers no)
		(fp_line
			(start -0.7874 0.4064)
			(end 0.7874 0.4064)
			(stroke
				(width 0.1524)
				(type default)
			)
			(layer "B.SilkS")
		)
		(fp_line
			(start 0.7874 0.4064)
			(end 0.7874 -0.4064)
			(stroke
				(width 0.1524)
				(type default)
			)
			(layer "B.SilkS")
		)
		(fp_line
			(start -0.7874 -0.4064)
			(end -0.7874 0.4064)
			(stroke
				(width 0.1524)
				(type default)
			)
			(layer "B.SilkS")
		)
		(fp_line
			(start 0.7874 -0.4064)
			(end -0.7874 -0.4064)
			(stroke
				(width 0.1524)
				(type default)
			)
			(layer "B.SilkS")
		)
		(fp_line
			(start -0.67945 0.3048)
			(end -0.120396 0.3048)
			(stroke
				(width 0.1)
				(type default)
			)
			(layer "B.Fab")
		)
		(fp_line
			(start -0.120396 0.3048)
			(end -0.120396 0.2794)
			(stroke
				(width 0.1)
				(type default)
			)
			(layer "B.Fab")
		)
		(fp_line
			(start 0.12065 0.3048)
			(end 0.67945 0.3048)
			(stroke
				(width 0.1)
				(type default)
			)
			(layer "B.Fab")
		)
		(fp_line
			(start 0.67945 0.3048)
			(end 0.67945 -0.305054)
			(stroke
				(width 0.1)
				(type default)
			)
			(layer "B.Fab")
		)
		(fp_line
			(start -0.120396 0.2794)
			(end 0.12065 0.2794)
			(stroke
				(width 0.1)
				(type default)
			)
			(layer "B.Fab")
		)
		(fp_line
			(start 0.12065 0.2794)
			(end 0.12065 0.3048)
			(stroke
				(width 0.1)
				(type default)
			)
			(layer "B.Fab")
		)
		(fp_line
			(start -0.12065 -0.2794)
			(end -0.12065 -0.3048)
			(stroke
				(width 0.1)
				(type default)
			)
			(layer "B.Fab")
		)
		(fp_line
			(start 0.12065 -0.2794)
			(end -0.12065 -0.2794)
			(stroke
				(width 0.1)
				(type default)
			)
			(layer "B.Fab")
		)
		(fp_line
			(start -0.67945 -0.3048)
			(end -0.67945 0.3048)
			(stroke
				(width 0.1)
				(type default)
			)
			(layer "B.Fab")
		)
		(fp_line
			(start -0.12065 -0.3048)
			(end -0.67945 -0.3048)
			(stroke
				(width 0.1)
				(type default)
			)
			(layer "B.Fab")
		)
		(fp_line
			(start 0.12065 -0.305054)
			(end 0.12065 -0.2794)
			(stroke
				(width 0.1)
				(type default)
			)
			(layer "B.Fab")
		)
		(fp_line
			(start 0.67945 -0.305054)
			(end 0.12065 -0.305054)
			(stroke
				(width 0.1)
				(type default)
			)
			(layer "B.Fab")
		)
		(pad "1" smd circle
			(at 0.40005 0 90)
			(size 0 0)
			(layers "B.Cu" "B.Mask" "B.Paste")
			(net "PWRGD_DRAMPWRGD_CPU1_GH_R_LVC1")
		)
		(pad "2" smd circle
			(at -0.40005 0 90)
			(size 0 0)
			(layers "B.Cu" "B.Mask" "B.Paste")
			(net "PWRGD_DRAMPWRGD_CPU1_GH_LVC1_R2")
		)
	)
)
